(kicad_pcb
	(version 20260206)
	(generator "pcbnew")
	(generator_version "10.0")
	(general
		(thickness 1.6)
		(legacy_teardrops no)
	)
	(paper "A4")
	(title_block
		(title "04192023_DAF0TMB3IC0_F0TG_MB_C_brd_V02_OCP.brd")
		(comment 1 "Grand Teton / footprints 701-702 of 8354")
	)
	(layers
		(0 "F.Cu" signal "TOP")
		(4 "In1.Cu" signal "GND")
		(6 "In2.Cu" signal "IN1")
		(8 "In3.Cu" signal "GND1")
		(10 "In4.Cu" signal "IN2")
		(12 "In5.Cu" signal "GND2")
		(14 "In6.Cu" signal "IN3")
		(16 "In7.Cu" signal "GND3")
		(18 "In8.Cu" signal "VCC")
		(20 "In9.Cu" signal "VCC1")
		(22 "In10.Cu" signal "GND4")
		(24 "In11.Cu" signal "IN4")
		(26 "In12.Cu" signal "GND5")
		(28 "In13.Cu" signal "IN5")
		(30 "In14.Cu" signal "GND6")
		(32 "In15.Cu" signal "IN6")
		(34 "In16.Cu" signal "GND7")
		(2 "B.Cu" signal "BOTTOM")
		(9 "F.Adhes" user "F.Adhesive")
		(11 "B.Adhes" user "B.Adhesive")
		(13 "F.Paste" user "Package Geometry/Pastemask Top")
		(15 "B.Paste" user "Package Geometry/Pastemask Bottom")
		(5 "F.SilkS" user "Ref Des/Silkscreen Top")
		(7 "B.SilkS" user "Ref Des/Silkscreen Bottom")
		(1 "F.Mask" user "Board Geometry/Soldermask Top")
		(3 "B.Mask" user "Board Geometry/Soldermask Bottom")
		(17 "Dwgs.User" user "User.Drawings")
		(19 "Cmts.User" user "User.Comments")
		(21 "Eco1.User" user "User.Eco1")
		(23 "Eco2.User" user "User.Eco2")
		(25 "Edge.Cuts" user "Board Geometry/Outline")
		(27 "Margin" user)
		(31 "F.CrtYd" user "Package Geometry/Place Bound Top")
		(29 "B.CrtYd" user "Package Geometry/Place Bound Bottom")
		(35 "F.Fab" user "Ref Des/Assembly Top")
		(33 "B.Fab" user "Ref Des/Assembly Bottom")
	)
	(footprint ""
		(layer "F.Cu")
		(at 279.527 -417.195 180)
		(property "Reference" "R4490"
			(at 0 0 180)
			(layer "F.SilkS")
			(hide yes)
			(effects
				(font
					(size 1.27 1.27)
				)
			)
		)
		(property "Value" ""
			(at 0 0 180)
			(layer "F.Fab")
			(effects
				(font
					(size 1.27 1.27)
				)
			)
		)
		(duplicate_pad_numbers_are_jumpers no)
		(fp_line
			(start 0.7874 0.4064)
			(end -0.7874 0.4064)
			(stroke
				(width 0.1524)
				(type default)
			)
			(layer "F.SilkS")
		)
		(fp_line
			(start 0.7874 -0.4064)
			(end 0.7874 0.4064)
			(stroke
				(width 0.1524)
				(type default)
			)
			(layer "F.SilkS")
		)
		(fp_line
			(start -0.7874 0.4064)
			(end -0.7874 -0.4064)
			(stroke
				(width 0.1524)
				(type default)
			)
			(layer "F.SilkS")
		)
		(fp_line
			(start -0.7874 -0.4064)
			(end 0.7874 -0.4064)
			(stroke
				(width 0.1524)
				(type default)
			)
			(layer "F.SilkS")
		)
		(fp_line
			(start 0.67945 0.3048)
			(end 0.120396 0.3048)
			(stroke
				(width 0.1)
				(type default)
			)
			(layer "F.Fab")
		)
		(fp_line
			(start 0.67945 -0.3048)
			(end 0.67945 0.3048)
			(stroke
				(width 0.1)
				(type default)
			)
			(layer "F.Fab")
		)
		(fp_line
			(start 0.12065 -0.2794)
			(end 0.12065 -0.3048)
			(stroke
				(width 0.1)
				(type default)
			)
			(layer "F.Fab")
		)
		(fp_line
			(start 0.12065 -0.3048)
			(end 0.67945 -0.3048)
			(stroke
				(width 0.1)
				(type default)
			)
			(layer "F.Fab")
		)
		(fp_line
			(start 0.120396 0.3048)
			(end 0.120396 0.2794)
			(stroke
				(width 0.1)
				(type default)
			)
			(layer "F.Fab")
		)
		(fp_line
			(start 0.120396 0.2794)
			(end -0.12065 0.2794)
			(stroke
				(width 0.1)
				(type default)
			)
			(layer "F.Fab")
		)
		(fp_line
			(start -0.12065 0.3048)
			(end -0.67945 0.3048)
			(stroke
				(width 0.1)
				(type default)
			)
			(layer "F.Fab")
		)
		(fp_line
			(start -0.12065 0.2794)
			(end -0.12065 0.3048)
			(stroke
				(width 0.1)
				(type default)
			)
			(layer "F.Fab")
		)
		(fp_line
			(start -0.12065 -0.2794)
			(end 0.12065 -0.2794)
			(stroke
				(width 0.1)
				(type default)
			)
			(layer "F.Fab")
		)
		(fp_line
			(start -0.12065 -0.305054)
			(end -0.12065 -0.2794)
			(stroke
				(width 0.1)
				(type default)
			)
			(layer "F.Fab")
		)
		(fp_line
			(start -0.67945 0.3048)
			(end -0.67945 -0.305054)
			(stroke
				(width 0.1)
				(type default)
			)
			(layer "F.Fab")
		)
		(fp_line
			(start -0.67945 -0.305054)
			(end -0.12065 -0.305054)
			(stroke
				(width 0.1)
				(type default)
			)
			(layer "F.Fab")
		)
		(pad "1" smd circle
			(at -0.40005 0 180)
			(size 0 0)
			(layers "F.Cu" "F.Mask" "F.Paste")
			(net "CLK_9ZXL045_P0_SADR0")
		)
		(pad "2" smd circle
			(at 0.40005 0 180)
			(size 0 0)
			(layers "F.Cu" "F.Mask" "F.Paste")
			(net "GND")
		)
	)
	(footprint ""
		(layer "F.Cu")
		(at 352.853244 -381.41783 -90)
		(property "Reference" "C942"
			(at 0 0 270)
			(layer "F.SilkS")
			(hide yes)
			(effects
				(font
					(size 1.27 1.27)
				)
			)
		)
		(property "Value" ""
			(at 0 0 270)
			(layer "F.Fab")
			(effects
				(font
					(size 1.27 1.27)
				)
			)
		)
		(duplicate_pad_numbers_are_jumpers no)
		(fp_line
			(start -0.299974 0.150114)
			(end -0.299974 -0.150114)
			(stroke
				(width 0.1)
				(type default)
			)
			(layer "F.Fab")
		)
		(fp_line
			(start 0.299974 0.150114)
			(end -0.299974 0.150114)
			(stroke
				(width 0.1)
				(type default)
			)
			(layer "F.Fab")
		)
		(fp_line
			(start -0.299974 -0.150114)
			(end 0.299974 -0.150114)
			(stroke
				(width 0.1)
				(type default)
			)
			(layer "F.Fab")
		)
		(fp_line
			(start 0.299974 -0.150114)
			(end 0.299974 0.150114)
			(stroke
				(width 0.1)
				(type default)
			)
			(layer "F.Fab")
		)
		(pad "1" smd rect
			(at -0.2667 0 270)
			(size 0.3048 0.381)
			(layers "F.Cu" "F.Mask" "F.Paste")
			(net "P5E_CPU0_P1_TX_C_DN<11>")
		)
		(pad "2" smd rect
			(at 0.2667 0 270)
			(size 0.3048 0.381)
			(layers "F.Cu" "F.Mask" "F.Paste")
			(net "P5E_CPU0_P1_TX_DN<11>")
		)
	)
)
